(kicad_pcb
	(version 20260206)
	(generator "pcbnew")
	(generator_version "10.0")
	(general
		(thickness 1.6)
		(legacy_teardrops no)
	)
	(paper "A4")
	(title_block
		(title "netronome-mezz — pcbd0082-001_rev01_jul9_a.brd")
		(comment 1 "Open CloudServer (Microsoft) / footprints 305-313 of 714")
	)
	(layers
		(0 "F.Cu" signal "TOP")
		(4 "In1.Cu" signal "02_GND")
		(6 "In2.Cu" signal "03_SIG")
		(8 "In3.Cu" signal "04_SIG")
		(10 "In4.Cu" signal "05_GND")
		(12 "In5.Cu" signal "06_PWR1")
		(14 "In6.Cu" signal "07_SIG")
		(16 "In7.Cu" signal "08_SIG")
		(18 "In8.Cu" signal "09_GND")
		(2 "B.Cu" signal "BOTTOM")
		(9 "F.Adhes" user "F.Adhesive")
		(11 "B.Adhes" user "B.Adhesive")
		(13 "F.Paste" user "Package Geometry/Pastemask Top")
		(15 "B.Paste" user "Package Geometry/Pastemask Bottom")
		(5 "F.SilkS" user "Ref Des/Silkscreen Top")
		(7 "B.SilkS" user "Ref Des/Silkscreen Bottom")
		(1 "F.Mask" user "Board Geometry/Soldermask Top")
		(3 "B.Mask" user "Board Geometry/Soldermask Bottom")
		(17 "Dwgs.User" user "User.Drawings")
		(19 "Cmts.User" user "User.Comments")
		(21 "Eco1.User" user "User.Eco1")
		(23 "Eco2.User" user "User.Eco2")
		(25 "Edge.Cuts" user "Board Geometry/Outline")
		(27 "Margin" user)
		(31 "F.CrtYd" user "Package Geometry/Place Bound Top")
		(29 "B.CrtYd" user "Package Geometry/Place Bound Bottom")
		(35 "F.Fab" user "Ref Des/Assembly Top")
		(33 "B.Fab" user "Ref Des/Assembly Bottom")
		(45 "User.4" user "COMPVAL_TYPE_BOTTOM")
	)
	(footprint ""
		(layer "F.Cu")
		(at 73.406 26.797 90)
		(property "Reference" "R338"
			(at 0 0 90)
			(layer "F.SilkS")
			(hide yes)
			(effects
				(font
					(size 1.27 1.27)
				)
			)
		)
		(property "Value" "4.75K"
			(at -0.148158 1.3462 180)
			(unlocked yes)
			(layer "F.Fab")
			(hide yes)
			(effects
				(font
					(size 1.27 0.9652)
					(thickness 0.000001)
				)
				(justify left)
			)
		)
		(property "Device Type" "REST4024"
			(at -0.148158 1.3462 180)
			(unlocked yes)
			(layer "F.Fab")
			(hide yes)
			(effects
				(font
					(size 1.27 0.9652)
					(thickness 0.000001)
				)
				(justify left)
			)
		)
		(duplicate_pad_numbers_are_jumpers no)
		(fp_poly
			(pts
				(xy 0.635 1.0668) (xy 0.635 -1.0668) (xy -0.635 -1.0668) (xy -0.635 1.0668)
			)
			(stroke
				(width 0)
				(type default)
			)
			(fill no)
			(layer "F.CrtYd")
		)
		(fp_line
			(start 0.254 -0.508)
			(end 0.254 0.508)
			(stroke
				(width 0.0254)
				(type default)
			)
			(layer "F.Fab")
		)
		(fp_line
			(start -0.254 -0.508)
			(end 0.254 -0.508)
			(stroke
				(width 0.0254)
				(type default)
			)
			(layer "F.Fab")
		)
		(fp_line
			(start 0.254 0.508)
			(end -0.254 0.508)
			(stroke
				(width 0.0254)
				(type default)
			)
			(layer "F.Fab")
		)
		(fp_line
			(start -0.254 0.508)
			(end -0.254 -0.508)
			(stroke
				(width 0.0254)
				(type default)
			)
			(layer "F.Fab")
		)
		(pad "1" smd rect
			(at 0 -0.4191 90)
			(size 0.508 0.5334)
			(layers "F.Cu" "F.Mask" "F.Paste")
			(net "12N3293")
		)
		(pad "2" smd rect
			(at 0 0.4191 90)
			(size 0.508 0.5334)
			(layers "F.Cu" "F.Mask" "F.Paste")
			(net "DDR_VDDQ")
		)
		(zone
			(layer "F.Cu")
			(hatch none 0.5)
			(connect_pads
				(clearance 0)
			)
			(min_thickness 0.25)
			(keepout
				(tracks not_allowed)
				(vias allowed)
				(pads allowed)
				(copperpour not_allowed)
				(footprints allowed)
			)
			(placement
				(enabled no)
				(sheetname "")
			)
			(fill
				(thermal_gap 0.5)
				(thermal_bridge_width 0.5)
				(island_removal_mode 0)
			)
			(polygon
				(pts
					(xy 73.3806 26.7716) (xy 73.4314 26.7716) (xy 73.4314 26.8224) (xy 73.3806 26.8224)
				)
			)
		)
	)
	(footprint ""
		(layer "F.Cu")
		(at 26.67 40.386 90)
		(property "Reference" "R1"
			(at 0 0 90)
			(layer "F.SilkS")
			(hide yes)
			(effects
				(font
					(size 1.27 1.27)
				)
			)
		)
		(property "Value" "121K"
			(at -0.148158 1.3462 180)
			(unlocked yes)
			(layer "F.Fab")
			(hide yes)
			(effects
				(font
					(size 1.27 0.9652)
					(thickness 0.000001)
				)
				(justify left)
			)
		)
		(property "Device Type" "REST0174"
			(at -0.148158 1.3462 180)
			(unlocked yes)
			(layer "F.Fab")
			(hide yes)
			(effects
				(font
					(size 1.27 0.9652)
					(thickness 0.000001)
				)
				(justify left)
			)
		)
		(duplicate_pad_numbers_are_jumpers no)
		(fp_poly
			(pts
				(xy 0.635 1.0668) (xy 0.635 -1.0668) (xy -0.635 -1.0668) (xy -0.635 1.0668)
			)
			(stroke
				(width 0)
				(type default)
			)
			(fill no)
			(layer "F.CrtYd")
		)
		(fp_line
			(start 0.254 -0.508)
			(end 0.254 0.508)
			(stroke
				(width 0.0254)
				(type default)
			)
			(layer "F.Fab")
		)
		(fp_line
			(start -0.254 -0.508)
			(end 0.254 -0.508)
			(stroke
				(width 0.0254)
				(type default)
			)
			(layer "F.Fab")
		)
		(fp_line
			(start 0.254 0.508)
			(end -0.254 0.508)
			(stroke
				(width 0.0254)
				(type default)
			)
			(layer "F.Fab")
		)
		(fp_line
			(start -0.254 0.508)
			(end -0.254 -0.508)
			(stroke
				(width 0.0254)
				(type default)
			)
			(layer "F.Fab")
		)
		(pad "1" smd rect
			(at 0 -0.4191 90)
			(size 0.508 0.5334)
			(layers "F.Cu" "F.Mask" "F.Paste")
			(net "GND")
		)
		(pad "2" smd rect
			(at 0 0.4191 90)
			(size 0.508 0.5334)
			(layers "F.Cu" "F.Mask" "F.Paste")
			(net "10N2411")
		)
		(zone
			(layer "F.Cu")
			(hatch none 0.5)
			(connect_pads
				(clearance 0)
			)
			(min_thickness 0.25)
			(keepout
				(tracks not_allowed)
				(vias allowed)
				(pads allowed)
				(copperpour not_allowed)
				(footprints allowed)
			)
			(placement
				(enabled no)
				(sheetname "")
			)
			(fill
				(thermal_gap 0.5)
				(thermal_bridge_width 0.5)
				(island_removal_mode 0)
			)
			(polygon
				(pts
					(xy 26.6446 40.3606) (xy 26.6954 40.3606) (xy 26.6954 40.4114) (xy 26.6446 40.4114)
				)
			)
		)
	)
	(footprint ""
		(layer "F.Cu")
		(at 35.814 43.942 -90)
		(property "Reference" "R329"
			(at 3.937 -0.40767 90)
			(unlocked yes)
			(layer "F.SilkS")
			(effects
				(font
					(size 0.7874 0.5842)
					(thickness 0.127)
				)
				(justify left)
			)
		)
		(property "Value" ""
			(at 0 0 270)
			(layer "F.Fab")
			(effects
				(font
					(size 1.27 1.27)
				)
			)
		)
		(duplicate_pad_numbers_are_jumpers no)
		(fp_line
			(start -0.0254 0.127)
			(end -0.0254 -0.127)
			(stroke
				(width 0.1016)
				(type default)
			)
			(layer "F.SilkS")
		)
		(fp_line
			(start 0.0254 0.127)
			(end -0.0254 0.127)
			(stroke
				(width 0.1016)
				(type default)
			)
			(layer "F.SilkS")
		)
		(fp_line
			(start -0.0254 -0.127)
			(end 0.0254 -0.127)
			(stroke
				(width 0.1016)
				(type default)
			)
			(layer "F.SilkS")
		)
		(fp_line
			(start 0.0254 -0.127)
			(end 0.0254 0.127)
			(stroke
				(width 0.1016)
				(type default)
			)
			(layer "F.SilkS")
		)
		(fp_poly
			(pts
				(xy 0.889 -0.4953) (xy 0.889 0.4953) (xy -0.889 0.4953) (xy -0.889 -0.4953)
			)
			(stroke
				(width 0)
				(type default)
			)
			(fill no)
			(layer "F.CrtYd")
		)
		(fp_line
			(start -0.508 0.254)
			(end 0.508 0.254)
			(stroke
				(width 0.0254)
				(type default)
			)
			(layer "F.Fab")
		)
		(fp_line
			(start 0.508 0.254)
			(end 0.508 -0.254)
			(stroke
				(width 0.0254)
				(type default)
			)
			(layer "F.Fab")
		)
		(fp_line
			(start -0.508 -0.254)
			(end -0.508 0.254)
			(stroke
				(width 0.0254)
				(type default)
			)
			(layer "F.Fab")
		)
		(fp_line
			(start 0.508 -0.254)
			(end -0.508 -0.254)
			(stroke
				(width 0.0254)
				(type default)
			)
			(layer "F.Fab")
		)
		(pad "1" smd rect
			(at -0.4699 0 270)
			(size 0.5334 0.508)
			(layers "F.Cu" "F.Mask" "F.Paste")
			(net "NFP_VDD_CORE_TCOMPA")
		)
		(pad "2" smd rect
			(at 0.4699 0 270)
			(size 0.5334 0.508)
			(layers "F.Cu" "F.Mask" "F.Paste")
			(net "NFP_VDD_CORE_TCOMPB")
		)
	)
	(footprint ""
		(layer "F.Cu")
		(at 27.178 42.164 90)
		(property "Reference" "R3"
			(at 0 0 90)
			(layer "F.SilkS")
			(hide yes)
			(effects
				(font
					(size 1.27 1.27)
				)
			)
		)
		(property "Value" "332K"
			(at -0.148158 1.3462 180)
			(unlocked yes)
			(layer "F.Fab")
			(hide yes)
			(effects
				(font
					(size 1.27 0.9652)
					(thickness 0.000001)
				)
				(justify left)
			)
		)
		(property "Device Type" "REST0121"
			(at -0.148158 1.3462 180)
			(unlocked yes)
			(layer "F.Fab")
			(hide yes)
			(effects
				(font
					(size 1.27 0.9652)
					(thickness 0.000001)
				)
				(justify left)
			)
		)
		(duplicate_pad_numbers_are_jumpers no)
		(fp_poly
			(pts
				(xy 0.635 1.0668) (xy 0.635 -1.0668) (xy -0.635 -1.0668) (xy -0.635 1.0668)
			)
			(stroke
				(width 0)
				(type default)
			)
			(fill no)
			(layer "F.CrtYd")
		)
		(fp_line
			(start 0.254 -0.508)
			(end 0.254 0.508)
			(stroke
				(width 0.0254)
				(type default)
			)
			(layer "F.Fab")
		)
		(fp_line
			(start -0.254 -0.508)
			(end 0.254 -0.508)
			(stroke
				(width 0.0254)
				(type default)
			)
			(layer "F.Fab")
		)
		(fp_line
			(start 0.254 0.508)
			(end -0.254 0.508)
			(stroke
				(width 0.0254)
				(type default)
			)
			(layer "F.Fab")
		)
		(fp_line
			(start -0.254 0.508)
			(end -0.254 -0.508)
			(stroke
				(width 0.0254)
				(type default)
			)
			(layer "F.Fab")
		)
		(pad "1" smd rect
			(at 0 -0.4191 90)
			(size 0.508 0.5334)
			(layers "F.Cu" "F.Mask" "F.Paste")
			(net "10N2407")
		)
		(pad "2" smd rect
			(at 0 0.4191 90)
			(size 0.508 0.5334)
			(layers "F.Cu" "F.Mask" "F.Paste")
			(net "10N2397")
		)
		(zone
			(layer "F.Cu")
			(hatch none 0.5)
			(connect_pads
				(clearance 0)
			)
			(min_thickness 0.25)
			(keepout
				(tracks not_allowed)
				(vias allowed)
				(pads allowed)
				(copperpour not_allowed)
				(footprints allowed)
			)
			(placement
				(enabled no)
				(sheetname "")
			)
			(fill
				(thermal_gap 0.5)
				(thermal_bridge_width 0.5)
				(island_removal_mode 0)
			)
			(polygon
				(pts
					(xy 27.1526 42.1386) (xy 27.2034 42.1386) (xy 27.2034 42.1894) (xy 27.1526 42.1894)
				)
			)
		)
	)
	(footprint ""
		(layer "F.Cu")
		(at 75.057 9.017 90)
		(property "Reference" "C212"
			(at -0.78867 -1.778 0)
			(unlocked yes)
			(layer "F.SilkS")
			(effects
				(font
					(size 0.7874 0.5842)
					(thickness 0.127)
				)
				(justify left)
			)
		)
		(property "Value" "1UF"
			(at -0.091846 0.2921 180)
			(unlocked yes)
			(layer "F.Fab")
			(hide yes)
			(effects
				(font
					(size 0.7874 0.5842)
					(thickness 0.2032)
				)
				(justify left)
			)
		)
		(property "Device Type" "CAPC0028"
			(at -0.091846 0.2921 180)
			(unlocked yes)
			(layer "F.Fab")
			(hide yes)
			(effects
				(font
					(size 0.7874 0.5842)
					(thickness 0.2032)
				)
				(justify left)
			)
		)
		(duplicate_pad_numbers_are_jumpers no)
		(fp_poly
			(pts
				(xy 0.635 1.0668) (xy 0.635 -1.0668) (xy -0.635 -1.0668) (xy -0.635 1.0668)
			)
			(stroke
				(width 0)
				(type default)
			)
			(fill no)
			(layer "F.CrtYd")
		)
		(fp_line
			(start 0.254 -0.508)
			(end 0.254 0.508)
			(stroke
				(width 0.0254)
				(type default)
			)
			(layer "F.Fab")
		)
		(fp_line
			(start -0.254 -0.508)
			(end 0.254 -0.508)
			(stroke
				(width 0.0254)
				(type default)
			)
			(layer "F.Fab")
		)
		(fp_line
			(start 0.254 0.508)
			(end -0.254 0.508)
			(stroke
				(width 0.0254)
				(type default)
			)
			(layer "F.Fab")
		)
		(fp_line
			(start -0.254 0.508)
			(end -0.254 -0.508)
			(stroke
				(width 0.0254)
				(type default)
			)
			(layer "F.Fab")
		)
		(pad "1" smd rect
			(at 0 -0.4191 90)
			(size 0.508 0.5334)
			(layers "F.Cu" "F.Mask" "F.Paste")
			(net "DDR_VDDQ")
		)
		(pad "2" smd rect
			(at 0 0.4191 90)
			(size 0.508 0.5334)
			(layers "F.Cu" "F.Mask" "F.Paste")
			(net "GND")
		)
		(zone
			(layer "F.Cu")
			(hatch none 0.5)
			(connect_pads
				(clearance 0)
			)
			(min_thickness 0.25)
			(keepout
				(tracks not_allowed)
				(vias allowed)
				(pads allowed)
				(copperpour not_allowed)
				(footprints allowed)
			)
			(placement
				(enabled no)
				(sheetname "")
			)
			(fill
				(thermal_gap 0.5)
				(thermal_bridge_width 0.5)
				(island_removal_mode 0)
			)
			(polygon
				(pts
					(xy 75.0316 8.9916) (xy 75.0824 8.9916) (xy 75.0824 9.0424) (xy 75.0316 9.0424)
				)
			)
		)
	)
	(footprint ""
		(layer "F.Cu")
		(at 73.05101 5.898998)
		(property "Reference" "V_A-DQS1-N"
			(at 0 0 0)
			(layer "F.SilkS")
			(hide yes)
			(effects
				(font
					(size 1.27 1.27)
				)
			)
		)
		(property "Value" ""
			(at 0 0 0)
			(layer "F.Fab")
			(effects
				(font
					(size 1.27 1.27)
				)
			)
		)
		(duplicate_pad_numbers_are_jumpers no)
		(pad "1" thru_hole circle
			(at 0 0)
			(size 0.762 0.762)
			(drill 0.20574)
			(layers "*.Cu" "*.Mask")
			(remove_unused_layers no)
			(net "DDR0_32A_DQS1_N")
			(clearance 0.127)
			(thermal_gap 0.127)
			(padstack
				(mode front_inner_back)
				(layer "Inner"
					(shape circle)
					(size 0.4572 0.4572)
					(clearance 0.1143)
				)
				(layer "B.Cu"
					(shape circle)
					(size 0.4572 0.4572)
					(clearance 0.1143)
				)
			)
		)
	)
	(footprint ""
		(layer "F.Cu")
		(at 25.908 36.83 -90)
		(property "Reference" "R85"
			(at 0 0 270)
			(layer "F.SilkS")
			(hide yes)
			(effects
				(font
					(size 1.27 1.27)
				)
			)
		)
		(property "Value" "4.75K"
			(at -0.148158 1.3462 0)
			(unlocked yes)
			(layer "F.Fab")
			(hide yes)
			(effects
				(font
					(size 1.27 0.9652)
					(thickness 0.000001)
				)
				(justify left)
			)
		)
		(property "Device Type" "REST4024"
			(at -0.148158 1.3462 0)
			(unlocked yes)
			(layer "F.Fab")
			(hide yes)
			(effects
				(font
					(size 1.27 0.9652)
					(thickness 0.000001)
				)
				(justify left)
			)
		)
		(duplicate_pad_numbers_are_jumpers no)
		(fp_poly
			(pts
				(xy 0.635 1.0668) (xy 0.635 -1.0668) (xy -0.635 -1.0668) (xy -0.635 1.0668)
			)
			(stroke
				(width 0)
				(type default)
			)
			(fill no)
			(layer "F.CrtYd")
		)
		(fp_line
			(start -0.254 0.508)
			(end -0.254 -0.508)
			(stroke
				(width 0.0254)
				(type default)
			)
			(layer "F.Fab")
		)
		(fp_line
			(start 0.254 0.508)
			(end -0.254 0.508)
			(stroke
				(width 0.0254)
				(type default)
			)
			(layer "F.Fab")
		)
		(fp_line
			(start -0.254 -0.508)
			(end 0.254 -0.508)
			(stroke
				(width 0.0254)
				(type default)
			)
			(layer "F.Fab")
		)
		(fp_line
			(start 0.254 -0.508)
			(end 0.254 0.508)
			(stroke
				(width 0.0254)
				(type default)
			)
			(layer "F.Fab")
		)
		(pad "1" smd rect
			(at 0 -0.4191 270)
			(size 0.508 0.5334)
			(layers "F.Cu" "F.Mask" "F.Paste")
			(net "CORE_FB_FAULT_L")
		)
		(pad "2" smd rect
			(at 0 0.4191 270)
			(size 0.508 0.5334)
			(layers "F.Cu" "F.Mask" "F.Paste")
			(net "EXT_3.3V")
		)
		(zone
			(layer "F.Cu")
			(hatch none 0.5)
			(connect_pads
				(clearance 0)
			)
			(min_thickness 0.25)
			(keepout
				(tracks not_allowed)
				(vias allowed)
				(pads allowed)
				(copperpour not_allowed)
				(footprints allowed)
			)
			(placement
				(enabled no)
				(sheetname "")
			)
			(fill
				(thermal_gap 0.5)
				(thermal_bridge_width 0.5)
				(island_removal_mode 0)
			)
			(polygon
				(pts
					(xy 25.9334 36.8554) (xy 25.8826 36.8554) (xy 25.8826 36.8046) (xy 25.9334 36.8046)
				)
			)
		)
	)
	(footprint ""
		(layer "F.Cu")
		(at 17.018 31.3055)
		(property "Reference" "L20"
			(at -2.25933 1.016 90)
			(unlocked yes)
			(layer "F.SilkS")
			(effects
				(font
					(size 0.7874 0.5842)
					(thickness 0.127)
				)
				(justify left)
			)
		)
		(property "Value" "1.0UH"
			(at -0.483362 -0.148082 0)
			(unlocked yes)
			(layer "F.Fab")
			(hide yes)
			(effects
				(font
					(size 1.27 0.9652)
					(thickness 0.000001)
				)
				(justify left)
			)
		)
		(property "Device Type" "INDS0061"
			(at -0.483362 -0.148082 0)
			(unlocked yes)
			(layer "F.Fab")
			(hide yes)
			(effects
				(font
					(size 1.27 0.9652)
					(thickness 0.000001)
				)
				(justify left)
			)
		)
		(duplicate_pad_numbers_are_jumpers no)
		(fp_line
			(start -1.27 -1.397)
			(end 1.27 -1.397)
			(stroke
				(width 0.1524)
				(type default)
			)
			(layer "F.SilkS")
		)
		(fp_line
			(start 1.27 1.397)
			(end -1.27 1.397)
			(stroke
				(width 0.1524)
				(type default)
			)
			(layer "F.SilkS")
		)
		(fp_poly
			(pts
				(xy 2.159 -1.651) (xy 2.159 1.651) (xy -2.159 1.651) (xy -2.159 -1.651)
			)
			(stroke
				(width 0)
				(type default)
			)
			(fill no)
			(layer "F.CrtYd")
		)
		(fp_line
			(start -1.3462 -1.1049)
			(end -1.3462 1.1049)
			(stroke
				(width 0.1524)
				(type default)
			)
			(layer "F.Fab")
		)
		(fp_line
			(start -1.3462 1.1049)
			(end 1.3462 1.1049)
			(stroke
				(width 0.1524)
				(type default)
			)
			(layer "F.Fab")
		)
		(fp_line
			(start 1.3462 -1.1049)
			(end -1.3462 -1.1049)
			(stroke
				(width 0.1524)
				(type default)
			)
			(layer "F.Fab")
		)
		(fp_line
			(start 1.3462 1.1049)
			(end 1.3462 -1.1049)
			(stroke
				(width 0.1524)
				(type default)
			)
			(layer "F.Fab")
		)
		(pad "1" smd rect
			(at -1.1303 0)
			(size 1.1938 2.3368)
			(layers "F.Cu" "F.Mask" "F.Paste")
			(net "11N2296")
		)
		(pad "2" smd rect
			(at 1.1303 0)
			(size 1.1938 2.3368)
			(layers "F.Cu" "F.Mask" "F.Paste")
			(net "VDD_3.3V")
		)
		(zone
			(layer "F.Cu")
			(hatch none 0.5)
			(connect_pads
				(clearance 0)
			)
			(min_thickness 0.25)
			(keepout
				(tracks allowed)
				(vias not_allowed)
				(pads allowed)
				(copperpour not_allowed)
				(footprints allowed)
			)
			(placement
				(enabled no)
				(sheetname "")
			)
			(fill
				(thermal_gap 0.5)
				(thermal_bridge_width 0.5)
				(island_removal_mode 0)
			)
			(polygon
				(pts
					(xy 15.6718 32.4104) (xy 18.3642 32.4104) (xy 18.3642 30.2006) (xy 15.6718 30.2006)
				)
			)
		)
	)
	(footprint ""
		(layer "B.Cu")
		(at 44.73702 14.042009 -90)
		(property "Reference" "C272"
			(at 0 0 90)
			(layer "B.SilkS")
			(hide yes)
			(effects
				(font
					(size 1.27 1.27)
				)
				(justify mirror)
			)
		)
		(property "Value" ""
			(at 0 0 90)
			(layer "B.Fab")
			(effects
				(font
					(size 1.27 1.27)
				)
				(justify mirror)
			)
		)
		(duplicate_pad_numbers_are_jumpers no)
		(fp_circle
			(center 0 0)
			(end 0 -0.104648)
			(stroke
				(width 0.1016)
				(type default)
			)
			(fill no)
			(layer "B.SilkS")
		)
		(fp_poly
			(pts
				(xy 0.381 -0.889) (xy 0.381 0.889) (xy -0.381 0.889) (xy -0.381 -0.889)
			)
			(stroke
				(width 0)
				(type default)
			)
			(fill no)
			(layer "B.CrtYd")
		)
		(fp_line
			(start -0.508 1.016)
			(end 0.508 1.016)
			(stroke
				(width 0.0254)
				(type default)
			)
			(layer "B.Fab")
		)
		(fp_line
			(start 0.508 1.016)
			(end 0.508 -1.016)
			(stroke
				(width 0.0254)
				(type default)
			)
			(layer "B.Fab")
		)
		(fp_line
			(start -0.508 -1.016)
			(end -0.508 1.016)
			(stroke
				(width 0.0254)
				(type default)
			)
			(layer "B.Fab")
		)
		(fp_line
			(start 0.254 -1.016)
			(end -0.508 -1.016)
			(stroke
				(width 0.0254)
				(type default)
			)
			(layer "B.Fab")
		)
		(fp_line
			(start 0.508 -1.016)
			(end 0.254 -1.016)
			(stroke
				(width 0.0254)
				(type default)
			)
			(layer "B.Fab")
		)
		(pad "1" smd custom
			(at 0 -0.500126 90)
			(size 0.127 0.127)
			(layers "B.Cu" "B.Mask" "B.Paste")
			(net "VDD_3.3V")
			(options
				(clearance outline)
				(anchor circle)
			)
			(primitives
				(gr_poly
					(pts
						(xy -0.1778 0.254) (xy 0.1778 0.254) (xy 0.254 0.1778) (xy 0.254 -0.1778) (xy 0.1778 -0.254) (xy -0.1778 -0.254)
						(xy -0.254 -0.1778) (xy -0.254 0.1778)
					)
					(width 0)
					(fill yes)
				)
			)
		)
		(pad "2" smd custom
			(at 0 0.500126 90)
			(size 0.127 0.127)
			(layers "B.Cu" "B.Mask" "B.Paste")
			(net "GND")
			(options
				(clearance outline)
				(anchor circle)
			)
			(primitives
				(gr_poly
					(pts
						(xy -0.1778 0.254) (xy 0.1778 0.254) (xy 0.254 0.1778) (xy 0.254 -0.1778) (xy 0.1778 -0.254) (xy -0.1778 -0.254)
						(xy -0.254 -0.1778) (xy -0.254 0.1778)
					)
					(width 0)
					(fill yes)
				)
			)
		)
	)
)
